(kicad_pcb
	(version 20260206)
	(generator "pcbnew")
	(generator_version "10.0")
	(general
		(thickness 1.6)
		(legacy_teardrops no)
	)
	(paper "A4")
	(title_block
		(title "04192023_DAF0TMB3IC0_F0TG_MB_C_brd_V02_OCP.brd")
		(comment 1 "Grand Teton / footprints 2006-2012 of 8354")
	)
	(layers
		(0 "F.Cu" signal "TOP")
		(4 "In1.Cu" signal "GND")
		(6 "In2.Cu" signal "IN1")
		(8 "In3.Cu" signal "GND1")
		(10 "In4.Cu" signal "IN2")
		(12 "In5.Cu" signal "GND2")
		(14 "In6.Cu" signal "IN3")
		(16 "In7.Cu" signal "GND3")
		(18 "In8.Cu" signal "VCC")
		(20 "In9.Cu" signal "VCC1")
		(22 "In10.Cu" signal "GND4")
		(24 "In11.Cu" signal "IN4")
		(26 "In12.Cu" signal "GND5")
		(28 "In13.Cu" signal "IN5")
		(30 "In14.Cu" signal "GND6")
		(32 "In15.Cu" signal "IN6")
		(34 "In16.Cu" signal "GND7")
		(2 "B.Cu" signal "BOTTOM")
		(9 "F.Adhes" user "F.Adhesive")
		(11 "B.Adhes" user "B.Adhesive")
		(13 "F.Paste" user "Package Geometry/Pastemask Top")
		(15 "B.Paste" user "Package Geometry/Pastemask Bottom")
		(5 "F.SilkS" user "Ref Des/Silkscreen Top")
		(7 "B.SilkS" user "Ref Des/Silkscreen Bottom")
		(1 "F.Mask" user "Board Geometry/Soldermask Top")
		(3 "B.Mask" user "Board Geometry/Soldermask Bottom")
		(17 "Dwgs.User" user "User.Drawings")
		(19 "Cmts.User" user "User.Comments")
		(21 "Eco1.User" user "User.Eco1")
		(23 "Eco2.User" user "User.Eco2")
		(25 "Edge.Cuts" user "Board Geometry/Outline")
		(27 "Margin" user)
		(31 "F.CrtYd" user "Package Geometry/Place Bound Top")
		(29 "B.CrtYd" user "Package Geometry/Place Bound Bottom")
		(35 "F.Fab" user "Ref Des/Assembly Top")
		(33 "B.Fab" user "Ref Des/Assembly Bottom")
	)
	(footprint ""
		(layer "F.Cu")
		(at 226.0981 -398.940782 180)
		(property "Reference" "PC2349"
			(at 0 0 180)
			(layer "F.SilkS")
			(hide yes)
			(effects
				(font
					(size 1.27 1.27)
				)
			)
		)
		(property "Value" ""
			(at 0 0 180)
			(layer "F.Fab")
			(effects
				(font
					(size 1.27 1.27)
				)
			)
		)
		(duplicate_pad_numbers_are_jumpers no)
		(fp_line
			(start 0.7874 0.4064)
			(end -0.7874 0.4064)
			(stroke
				(width 0.1524)
				(type default)
			)
			(layer "F.SilkS")
		)
		(fp_line
			(start 0.7874 -0.4064)
			(end 0.7874 0.4064)
			(stroke
				(width 0.1524)
				(type default)
			)
			(layer "F.SilkS")
		)
		(fp_line
			(start -0.7874 0.4064)
			(end -0.7874 -0.4064)
			(stroke
				(width 0.1524)
				(type default)
			)
			(layer "F.SilkS")
		)
		(fp_line
			(start -0.7874 -0.4064)
			(end 0.7874 -0.4064)
			(stroke
				(width 0.1524)
				(type default)
			)
			(layer "F.SilkS")
		)
		(fp_line
			(start 0.67945 0.3048)
			(end 0.120396 0.3048)
			(stroke
				(width 0.1)
				(type default)
			)
			(layer "F.Fab")
		)
		(fp_line
			(start 0.67945 -0.3048)
			(end 0.67945 0.3048)
			(stroke
				(width 0.1)
				(type default)
			)
			(layer "F.Fab")
		)
		(fp_line
			(start 0.12065 -0.2794)
			(end 0.12065 -0.3048)
			(stroke
				(width 0.1)
				(type default)
			)
			(layer "F.Fab")
		)
		(fp_line
			(start 0.12065 -0.3048)
			(end 0.67945 -0.3048)
			(stroke
				(width 0.1)
				(type default)
			)
			(layer "F.Fab")
		)
		(fp_line
			(start 0.120396 0.3048)
			(end 0.120396 0.2794)
			(stroke
				(width 0.1)
				(type default)
			)
			(layer "F.Fab")
		)
		(fp_line
			(start 0.120396 0.2794)
			(end -0.12065 0.2794)
			(stroke
				(width 0.1)
				(type default)
			)
			(layer "F.Fab")
		)
		(fp_line
			(start -0.12065 0.3048)
			(end -0.67945 0.3048)
			(stroke
				(width 0.1)
				(type default)
			)
			(layer "F.Fab")
		)
		(fp_line
			(start -0.12065 0.2794)
			(end -0.12065 0.3048)
			(stroke
				(width 0.1)
				(type default)
			)
			(layer "F.Fab")
		)
		(fp_line
			(start -0.12065 -0.2794)
			(end 0.12065 -0.2794)
			(stroke
				(width 0.1)
				(type default)
			)
			(layer "F.Fab")
		)
		(fp_line
			(start -0.12065 -0.305054)
			(end -0.12065 -0.2794)
			(stroke
				(width 0.1)
				(type default)
			)
			(layer "F.Fab")
		)
		(fp_line
			(start -0.67945 0.3048)
			(end -0.67945 -0.305054)
			(stroke
				(width 0.1)
				(type default)
			)
			(layer "F.Fab")
		)
		(fp_line
			(start -0.67945 -0.305054)
			(end -0.12065 -0.305054)
			(stroke
				(width 0.1)
				(type default)
			)
			(layer "F.Fab")
		)
		(pad "1" smd circle
			(at -0.40005 0 180)
			(size 0 0)
			(layers "F.Cu" "F.Mask" "F.Paste")
			(net "HSC_OCREF")
		)
		(pad "2" smd circle
			(at 0.40005 0 180)
			(size 0 0)
			(layers "F.Cu" "F.Mask" "F.Paste")
			(net "AGND_HSC")
		)
	)
	(footprint ""
		(layer "F.Cu")
		(at 430.355756 -109.25937 -90)
		(property "Reference" "PC2093"
			(at 0 0 270)
			(layer "F.SilkS")
			(hide yes)
			(effects
				(font
					(size 1.27 1.27)
				)
			)
		)
		(property "Value" ""
			(at 0 0 270)
			(layer "F.Fab")
			(effects
				(font
					(size 1.27 1.27)
				)
			)
		)
		(duplicate_pad_numbers_are_jumpers no)
		(fp_line
			(start -0.7874 0.4064)
			(end -0.7874 -0.4064)
			(stroke
				(width 0.1524)
				(type default)
			)
			(layer "F.SilkS")
		)
		(fp_line
			(start 0.7874 0.4064)
			(end -0.7874 0.4064)
			(stroke
				(width 0.1524)
				(type default)
			)
			(layer "F.SilkS")
		)
		(fp_line
			(start -0.7874 -0.4064)
			(end 0.7874 -0.4064)
			(stroke
				(width 0.1524)
				(type default)
			)
			(layer "F.SilkS")
		)
		(fp_line
			(start 0.7874 -0.4064)
			(end 0.7874 0.4064)
			(stroke
				(width 0.1524)
				(type default)
			)
			(layer "F.SilkS")
		)
		(fp_line
			(start -0.67945 0.3048)
			(end -0.67945 -0.305054)
			(stroke
				(width 0.1)
				(type default)
			)
			(layer "F.Fab")
		)
		(fp_line
			(start -0.12065 0.3048)
			(end -0.67945 0.3048)
			(stroke
				(width 0.1)
				(type default)
			)
			(layer "F.Fab")
		)
		(fp_line
			(start 0.120396 0.3048)
			(end 0.120396 0.2794)
			(stroke
				(width 0.1)
				(type default)
			)
			(layer "F.Fab")
		)
		(fp_line
			(start 0.67945 0.3048)
			(end 0.120396 0.3048)
			(stroke
				(width 0.1)
				(type default)
			)
			(layer "F.Fab")
		)
		(fp_line
			(start -0.12065 0.2794)
			(end -0.12065 0.3048)
			(stroke
				(width 0.1)
				(type default)
			)
			(layer "F.Fab")
		)
		(fp_line
			(start 0.120396 0.2794)
			(end -0.12065 0.2794)
			(stroke
				(width 0.1)
				(type default)
			)
			(layer "F.Fab")
		)
		(fp_line
			(start -0.12065 -0.2794)
			(end 0.12065 -0.2794)
			(stroke
				(width 0.1)
				(type default)
			)
			(layer "F.Fab")
		)
		(fp_line
			(start 0.12065 -0.2794)
			(end 0.12065 -0.3048)
			(stroke
				(width 0.1)
				(type default)
			)
			(layer "F.Fab")
		)
		(fp_line
			(start 0.12065 -0.3048)
			(end 0.67945 -0.3048)
			(stroke
				(width 0.1)
				(type default)
			)
			(layer "F.Fab")
		)
		(fp_line
			(start 0.67945 -0.3048)
			(end 0.67945 0.3048)
			(stroke
				(width 0.1)
				(type default)
			)
			(layer "F.Fab")
		)
		(fp_line
			(start -0.67945 -0.305054)
			(end -0.12065 -0.305054)
			(stroke
				(width 0.1)
				(type default)
			)
			(layer "F.Fab")
		)
		(fp_line
			(start -0.12065 -0.305054)
			(end -0.12065 -0.2794)
			(stroke
				(width 0.1)
				(type default)
			)
			(layer "F.Fab")
		)
		(pad "1" smd circle
			(at -0.40005 0 270)
			(size 0 0)
			(layers "F.Cu" "F.Mask" "F.Paste")
			(net "GND")
		)
		(pad "2" smd circle
			(at 0.40005 0 270)
			(size 0 0)
			(layers "F.Cu" "F.Mask" "F.Paste")
			(net "P3V3_OCP_REG_1")
		)
	)
	(footprint ""
		(layer "F.Cu")
		(at 299.265594 -393.96416)
		(property "Reference" "R979"
			(at 0 0 0)
			(layer "F.SilkS")
			(hide yes)
			(effects
				(font
					(size 1.27 1.27)
				)
			)
		)
		(property "Value" ""
			(at 0 0 0)
			(layer "F.Fab")
			(effects
				(font
					(size 1.27 1.27)
				)
			)
		)
		(duplicate_pad_numbers_are_jumpers no)
		(fp_line
			(start -0.32512 -0.175006)
			(end 0.32512 -0.175006)
			(stroke
				(width 0.1)
				(type default)
			)
			(layer "F.Fab")
		)
		(fp_line
			(start -0.32512 0.175006)
			(end -0.32512 -0.175006)
			(stroke
				(width 0.1)
				(type default)
			)
			(layer "F.Fab")
		)
		(fp_line
			(start 0.32512 -0.175006)
			(end 0.32512 0.175006)
			(stroke
				(width 0.1)
				(type default)
			)
			(layer "F.Fab")
		)
		(fp_line
			(start 0.32512 0.175006)
			(end -0.32512 0.175006)
			(stroke
				(width 0.1)
				(type default)
			)
			(layer "F.Fab")
		)
		(pad "1" smd rect
			(at -0.2667 0)
			(size 0.3048 0.381)
			(layers "F.Cu" "F.Mask" "F.Paste")
			(net "GPIO2_RT_CPU0_P0")
		)
		(pad "2" smd rect
			(at 0.2667 0 180)
			(size 0.3048 0.381)
			(layers "F.Cu" "F.Mask" "F.Paste")
			(net "GND")
		)
	)
	(footprint ""
		(layer "F.Cu")
		(at 41.995852 -385.58216)
		(property "Reference" "R706"
			(at 0 0 0)
			(layer "F.SilkS")
			(hide yes)
			(effects
				(font
					(size 1.27 1.27)
				)
			)
		)
		(property "Value" ""
			(at 0 0 0)
			(layer "F.Fab")
			(effects
				(font
					(size 1.27 1.27)
				)
			)
		)
		(duplicate_pad_numbers_are_jumpers no)
		(fp_line
			(start -0.32512 -0.175006)
			(end 0.32512 -0.175006)
			(stroke
				(width 0.1)
				(type default)
			)
			(layer "F.Fab")
		)
		(fp_line
			(start -0.32512 0.175006)
			(end -0.32512 -0.175006)
			(stroke
				(width 0.1)
				(type default)
			)
			(layer "F.Fab")
		)
		(fp_line
			(start 0.32512 -0.175006)
			(end 0.32512 0.175006)
			(stroke
				(width 0.1)
				(type default)
			)
			(layer "F.Fab")
		)
		(fp_line
			(start 0.32512 0.175006)
			(end -0.32512 0.175006)
			(stroke
				(width 0.1)
				(type default)
			)
			(layer "F.Fab")
		)
		(pad "1" smd rect
			(at -0.2667 0)
			(size 0.3048 0.381)
			(layers "F.Cu" "F.Mask" "F.Paste")
			(net "P1V8_CPU1_RT_1D")
		)
		(pad "2" smd rect
			(at 0.2667 0 180)
			(size 0.3048 0.381)
			(layers "F.Cu" "F.Mask" "F.Paste")
			(net "GPIO2_RT_CPU1_P0")
		)
	)
	(footprint ""
		(layer "F.Cu")
		(at 323.007482 -331.983842 180)
		(property "Reference" "PC190"
			(at 0 0 180)
			(layer "F.SilkS")
			(hide yes)
			(effects
				(font
					(size 1.27 1.27)
				)
			)
		)
		(property "Value" ""
			(at 0 0 180)
			(layer "F.Fab")
			(effects
				(font
					(size 1.27 1.27)
				)
			)
		)
		(duplicate_pad_numbers_are_jumpers no)
		(fp_line
			(start 0.7874 0.4064)
			(end -0.7874 0.4064)
			(stroke
				(width 0.1524)
				(type default)
			)
			(layer "F.SilkS")
		)
		(fp_line
			(start 0.7874 -0.4064)
			(end 0.7874 0.4064)
			(stroke
				(width 0.1524)
				(type default)
			)
			(layer "F.SilkS")
		)
		(fp_line
			(start -0.7874 0.4064)
			(end -0.7874 -0.4064)
			(stroke
				(width 0.1524)
				(type default)
			)
			(layer "F.SilkS")
		)
		(fp_line
			(start -0.7874 -0.4064)
			(end 0.7874 -0.4064)
			(stroke
				(width 0.1524)
				(type default)
			)
			(layer "F.SilkS")
		)
		(fp_line
			(start 0.67945 0.3048)
			(end 0.120396 0.3048)
			(stroke
				(width 0.1)
				(type default)
			)
			(layer "F.Fab")
		)
		(fp_line
			(start 0.67945 -0.3048)
			(end 0.67945 0.3048)
			(stroke
				(width 0.1)
				(type default)
			)
			(layer "F.Fab")
		)
		(fp_line
			(start 0.12065 -0.2794)
			(end 0.12065 -0.3048)
			(stroke
				(width 0.1)
				(type default)
			)
			(layer "F.Fab")
		)
		(fp_line
			(start 0.12065 -0.3048)
			(end 0.67945 -0.3048)
			(stroke
				(width 0.1)
				(type default)
			)
			(layer "F.Fab")
		)
		(fp_line
			(start 0.120396 0.3048)
			(end 0.120396 0.2794)
			(stroke
				(width 0.1)
				(type default)
			)
			(layer "F.Fab")
		)
		(fp_line
			(start 0.120396 0.2794)
			(end -0.12065 0.2794)
			(stroke
				(width 0.1)
				(type default)
			)
			(layer "F.Fab")
		)
		(fp_line
			(start -0.12065 0.3048)
			(end -0.67945 0.3048)
			(stroke
				(width 0.1)
				(type default)
			)
			(layer "F.Fab")
		)
		(fp_line
			(start -0.12065 0.2794)
			(end -0.12065 0.3048)
			(stroke
				(width 0.1)
				(type default)
			)
			(layer "F.Fab")
		)
		(fp_line
			(start -0.12065 -0.2794)
			(end 0.12065 -0.2794)
			(stroke
				(width 0.1)
				(type default)
			)
			(layer "F.Fab")
		)
		(fp_line
			(start -0.12065 -0.305054)
			(end -0.12065 -0.2794)
			(stroke
				(width 0.1)
				(type default)
			)
			(layer "F.Fab")
		)
		(fp_line
			(start -0.67945 0.3048)
			(end -0.67945 -0.305054)
			(stroke
				(width 0.1)
				(type default)
			)
			(layer "F.Fab")
		)
		(fp_line
			(start -0.67945 -0.305054)
			(end -0.12065 -0.305054)
			(stroke
				(width 0.1)
				(type default)
			)
			(layer "F.Fab")
		)
		(pad "1" smd circle
			(at -0.40005 0 180)
			(size 0 0)
			(layers "F.Cu" "F.Mask" "F.Paste")
			(net "SW_PVDDCR_CPU1_P0_SW2")
		)
		(pad "2" smd circle
			(at 0.40005 0 180)
			(size 0 0)
			(layers "F.Cu" "F.Mask" "F.Paste")
			(net "SW_PVDDCR_CPU1_P0_SW2_RC")
		)
	)
	(footprint ""
		(layer "F.Cu")
		(at 206.381604 -342.075262 -90)
		(property "Reference" "PC132"
			(at 0 0 270)
			(layer "F.SilkS")
			(hide yes)
			(effects
				(font
					(size 1.27 1.27)
				)
			)
		)
		(property "Value" ""
			(at 0 0 270)
			(layer "F.Fab")
			(effects
				(font
					(size 1.27 1.27)
				)
			)
		)
		(duplicate_pad_numbers_are_jumpers no)
		(fp_line
			(start -0.7874 0.4064)
			(end -0.7874 -0.4064)
			(stroke
				(width 0.1524)
				(type default)
			)
			(layer "F.SilkS")
		)
		(fp_line
			(start 0.7874 0.4064)
			(end -0.7874 0.4064)
			(stroke
				(width 0.1524)
				(type default)
			)
			(layer "F.SilkS")
		)
		(fp_line
			(start -0.7874 -0.4064)
			(end 0.7874 -0.4064)
			(stroke
				(width 0.1524)
				(type default)
			)
			(layer "F.SilkS")
		)
		(fp_line
			(start 0.7874 -0.4064)
			(end 0.7874 0.4064)
			(stroke
				(width 0.1524)
				(type default)
			)
			(layer "F.SilkS")
		)
		(fp_line
			(start -0.67945 0.3048)
			(end -0.67945 -0.305054)
			(stroke
				(width 0.1)
				(type default)
			)
			(layer "F.Fab")
		)
		(fp_line
			(start -0.12065 0.3048)
			(end -0.67945 0.3048)
			(stroke
				(width 0.1)
				(type default)
			)
			(layer "F.Fab")
		)
		(fp_line
			(start 0.120396 0.3048)
			(end 0.120396 0.2794)
			(stroke
				(width 0.1)
				(type default)
			)
			(layer "F.Fab")
		)
		(fp_line
			(start 0.67945 0.3048)
			(end 0.120396 0.3048)
			(stroke
				(width 0.1)
				(type default)
			)
			(layer "F.Fab")
		)
		(fp_line
			(start -0.12065 0.2794)
			(end -0.12065 0.3048)
			(stroke
				(width 0.1)
				(type default)
			)
			(layer "F.Fab")
		)
		(fp_line
			(start 0.120396 0.2794)
			(end -0.12065 0.2794)
			(stroke
				(width 0.1)
				(type default)
			)
			(layer "F.Fab")
		)
		(fp_line
			(start -0.12065 -0.2794)
			(end 0.12065 -0.2794)
			(stroke
				(width 0.1)
				(type default)
			)
			(layer "F.Fab")
		)
		(fp_line
			(start 0.12065 -0.2794)
			(end 0.12065 -0.3048)
			(stroke
				(width 0.1)
				(type default)
			)
			(layer "F.Fab")
		)
		(fp_line
			(start 0.12065 -0.3048)
			(end 0.67945 -0.3048)
			(stroke
				(width 0.1)
				(type default)
			)
			(layer "F.Fab")
		)
		(fp_line
			(start 0.67945 -0.3048)
			(end 0.67945 0.3048)
			(stroke
				(width 0.1)
				(type default)
			)
			(layer "F.Fab")
		)
		(fp_line
			(start -0.67945 -0.305054)
			(end -0.12065 -0.305054)
			(stroke
				(width 0.1)
				(type default)
			)
			(layer "F.Fab")
		)
		(fp_line
			(start -0.12065 -0.305054)
			(end -0.12065 -0.2794)
			(stroke
				(width 0.1)
				(type default)
			)
			(layer "F.Fab")
		)
		(pad "1" smd circle
			(at -0.40005 0 270)
			(size 0 0)
			(layers "F.Cu" "F.Mask" "F.Paste")
			(net "PVDD_33_S5_FB")
		)
		(pad "2" smd circle
			(at 0.40005 0 270)
			(size 0 0)
			(layers "F.Cu" "F.Mask" "F.Paste")
			(net "PVDD_33_S5")
		)
	)
	(footprint ""
		(layer "F.Cu")
		(at 204.7621 -399.956782)
		(property "Reference" "PR3919"
			(at 0 0 0)
			(layer "F.SilkS")
			(hide yes)
			(effects
				(font
					(size 1.27 1.27)
				)
			)
		)
		(property "Value" ""
			(at 0 0 0)
			(layer "F.Fab")
			(effects
				(font
					(size 1.27 1.27)
				)
			)
		)
		(duplicate_pad_numbers_are_jumpers no)
		(fp_line
			(start -0.7874 -0.4064)
			(end 0.7874 -0.4064)
			(stroke
				(width 0.1524)
				(type default)
			)
			(layer "F.SilkS")
		)
		(fp_line
			(start -0.7874 0.4064)
			(end -0.7874 -0.4064)
			(stroke
				(width 0.1524)
				(type default)
			)
			(layer "F.SilkS")
		)
		(fp_line
			(start 0.7874 -0.4064)
			(end 0.7874 0.4064)
			(stroke
				(width 0.1524)
				(type default)
			)
			(layer "F.SilkS")
		)
		(fp_line
			(start 0.7874 0.4064)
			(end -0.7874 0.4064)
			(stroke
				(width 0.1524)
				(type default)
			)
			(layer "F.SilkS")
		)
		(fp_line
			(start -0.67945 -0.305054)
			(end -0.12065 -0.305054)
			(stroke
				(width 0.1)
				(type default)
			)
			(layer "F.Fab")
		)
		(fp_line
			(start -0.67945 0.3048)
			(end -0.67945 -0.305054)
			(stroke
				(width 0.1)
				(type default)
			)
			(layer "F.Fab")
		)
		(fp_line
			(start -0.12065 -0.305054)
			(end -0.12065 -0.2794)
			(stroke
				(width 0.1)
				(type default)
			)
			(layer "F.Fab")
		)
		(fp_line
			(start -0.12065 -0.2794)
			(end 0.12065 -0.2794)
			(stroke
				(width 0.1)
				(type default)
			)
			(layer "F.Fab")
		)
		(fp_line
			(start -0.12065 0.2794)
			(end -0.12065 0.3048)
			(stroke
				(width 0.1)
				(type default)
			)
			(layer "F.Fab")
		)
		(fp_line
			(start -0.12065 0.3048)
			(end -0.67945 0.3048)
			(stroke
				(width 0.1)
				(type default)
			)
			(layer "F.Fab")
		)
		(fp_line
			(start 0.120396 0.2794)
			(end -0.12065 0.2794)
			(stroke
				(width 0.1)
				(type default)
			)
			(layer "F.Fab")
		)
		(fp_line
			(start 0.120396 0.3048)
			(end 0.120396 0.2794)
			(stroke
				(width 0.1)
				(type default)
			)
			(layer "F.Fab")
		)
		(fp_line
			(start 0.12065 -0.3048)
			(end 0.67945 -0.3048)
			(stroke
				(width 0.1)
				(type default)
			)
			(layer "F.Fab")
		)
		(fp_line
			(start 0.12065 -0.2794)
			(end 0.12065 -0.3048)
			(stroke
				(width 0.1)
				(type default)
			)
			(layer "F.Fab")
		)
		(fp_line
			(start 0.67945 -0.3048)
			(end 0.67945 0.3048)
			(stroke
				(width 0.1)
				(type default)
			)
			(layer "F.Fab")
		)
		(fp_line
			(start 0.67945 0.3048)
			(end 0.120396 0.3048)
			(stroke
				(width 0.1)
				(type default)
			)
			(layer "F.Fab")
		)
		(pad "1" smd circle
			(at -0.40005 0)
			(size 0 0)
			(layers "F.Cu" "F.Mask" "F.Paste")
			(net "HSC_D_OC_1")
		)
		(pad "2" smd circle
			(at 0.40005 0)
			(size 0 0)
			(layers "F.Cu" "F.Mask" "F.Paste")
			(net "HSC_D_OC_R")
		)
	)
)
